(kicad_pcb
	(version 20260206)
	(generator "pcbnew")
	(generator_version "10.0")
	(general
		(thickness 1.6)
		(legacy_teardrops no)
	)
	(paper "A4")
	(title_block
		(title "04192023_DAF0TMB3IC0_F0TG_MB_C_brd_V02_OCP.brd")
		(comment 1 "Grand Teton / footprints 5600-5606 of 8354")
	)
	(layers
		(0 "F.Cu" signal "TOP")
		(4 "In1.Cu" signal "GND")
		(6 "In2.Cu" signal "IN1")
		(8 "In3.Cu" signal "GND1")
		(10 "In4.Cu" signal "IN2")
		(12 "In5.Cu" signal "GND2")
		(14 "In6.Cu" signal "IN3")
		(16 "In7.Cu" signal "GND3")
		(18 "In8.Cu" signal "VCC")
		(20 "In9.Cu" signal "VCC1")
		(22 "In10.Cu" signal "GND4")
		(24 "In11.Cu" signal "IN4")
		(26 "In12.Cu" signal "GND5")
		(28 "In13.Cu" signal "IN5")
		(30 "In14.Cu" signal "GND6")
		(32 "In15.Cu" signal "IN6")
		(34 "In16.Cu" signal "GND7")
		(2 "B.Cu" signal "BOTTOM")
		(9 "F.Adhes" user "F.Adhesive")
		(11 "B.Adhes" user "B.Adhesive")
		(13 "F.Paste" user "Package Geometry/Pastemask Top")
		(15 "B.Paste" user "Package Geometry/Pastemask Bottom")
		(5 "F.SilkS" user "Ref Des/Silkscreen Top")
		(7 "B.SilkS" user "Ref Des/Silkscreen Bottom")
		(1 "F.Mask" user "Board Geometry/Soldermask Top")
		(3 "B.Mask" user "Board Geometry/Soldermask Bottom")
		(17 "Dwgs.User" user "User.Drawings")
		(19 "Cmts.User" user "User.Comments")
		(21 "Eco1.User" user "User.Eco1")
		(23 "Eco2.User" user "User.Eco2")
		(25 "Edge.Cuts" user "Board Geometry/Outline")
		(27 "Margin" user)
		(31 "F.CrtYd" user "Package Geometry/Place Bound Top")
		(29 "B.CrtYd" user "Package Geometry/Place Bound Bottom")
		(35 "F.Fab" user "Ref Des/Assembly Top")
		(33 "B.Fab" user "Ref Des/Assembly Bottom")
	)
	(footprint ""
		(layer "B.Cu")
		(at 70.876668 -177.513234 -90)
		(property "Reference" "PC312_5"
			(at 0 0 90)
			(layer "B.SilkS")
			(hide yes)
			(effects
				(font
					(size 1.27 1.27)
				)
				(justify mirror)
			)
		)
		(property "Value" ""
			(at 0 0 90)
			(layer "B.Fab")
			(effects
				(font
					(size 1.27 1.27)
				)
				(justify mirror)
			)
		)
		(duplicate_pad_numbers_are_jumpers no)
		(fp_line
			(start -1.524 0.762)
			(end 1.524 0.762)
			(stroke
				(width 0.1524)
				(type default)
			)
			(layer "B.SilkS")
		)
		(fp_line
			(start 1.524 0.762)
			(end 1.524 -0.762)
			(stroke
				(width 0.1524)
				(type default)
			)
			(layer "B.SilkS")
		)
		(fp_line
			(start -1.524 -0.762)
			(end -1.524 0.762)
			(stroke
				(width 0.1524)
				(type default)
			)
			(layer "B.SilkS")
		)
		(fp_line
			(start 1.524 -0.762)
			(end -1.524 -0.762)
			(stroke
				(width 0.1524)
				(type default)
			)
			(layer "B.SilkS")
		)
		(fp_line
			(start -1.1049 0.724916)
			(end -1.1049 -0.724916)
			(stroke
				(width 0.1)
				(type default)
			)
			(layer "B.Fab")
		)
		(fp_line
			(start 1.1049 0.724916)
			(end -1.1049 0.724916)
			(stroke
				(width 0.1)
				(type default)
			)
			(layer "B.Fab")
		)
		(fp_line
			(start -1.1049 -0.724916)
			(end 1.1049 -0.724916)
			(stroke
				(width 0.1)
				(type default)
			)
			(layer "B.Fab")
		)
		(fp_line
			(start 1.1049 -0.724916)
			(end 1.1049 0.724916)
			(stroke
				(width 0.1)
				(type default)
			)
			(layer "B.Fab")
		)
		(pad "1" smd rect
			(at 0.889 0 270)
			(size 1.016 1.27)
			(layers "B.Cu" "B.Mask" "B.Paste")
			(net "SW_P12V_AUX_PVDDCR_CPU0_P1_FLT")
		)
		(pad "2" smd rect
			(at -0.889 0 270)
			(size 1.016 1.27)
			(layers "B.Cu" "B.Mask" "B.Paste")
			(net "GND")
		)
	)
	(footprint ""
		(layer "B.Cu")
		(at 306.385214 -347.77553 -90)
		(property "Reference" "PR87"
			(at 0 0 90)
			(layer "B.SilkS")
			(hide yes)
			(effects
				(font
					(size 1.27 1.27)
				)
				(justify mirror)
			)
		)
		(property "Value" ""
			(at 0 0 90)
			(layer "B.Fab")
			(effects
				(font
					(size 1.27 1.27)
				)
				(justify mirror)
			)
		)
		(duplicate_pad_numbers_are_jumpers no)
		(fp_line
			(start -0.7874 0.4064)
			(end 0.7874 0.4064)
			(stroke
				(width 0.1524)
				(type default)
			)
			(layer "B.SilkS")
		)
		(fp_line
			(start 0.7874 0.4064)
			(end 0.7874 -0.4064)
			(stroke
				(width 0.1524)
				(type default)
			)
			(layer "B.SilkS")
		)
		(fp_line
			(start -0.7874 -0.4064)
			(end -0.7874 0.4064)
			(stroke
				(width 0.1524)
				(type default)
			)
			(layer "B.SilkS")
		)
		(fp_line
			(start 0.7874 -0.4064)
			(end -0.7874 -0.4064)
			(stroke
				(width 0.1524)
				(type default)
			)
			(layer "B.SilkS")
		)
		(fp_line
			(start -0.67945 0.3048)
			(end -0.120396 0.3048)
			(stroke
				(width 0.1)
				(type default)
			)
			(layer "B.Fab")
		)
		(fp_line
			(start -0.120396 0.3048)
			(end -0.120396 0.2794)
			(stroke
				(width 0.1)
				(type default)
			)
			(layer "B.Fab")
		)
		(fp_line
			(start 0.12065 0.3048)
			(end 0.67945 0.3048)
			(stroke
				(width 0.1)
				(type default)
			)
			(layer "B.Fab")
		)
		(fp_line
			(start 0.67945 0.3048)
			(end 0.67945 -0.305054)
			(stroke
				(width 0.1)
				(type default)
			)
			(layer "B.Fab")
		)
		(fp_line
			(start -0.120396 0.2794)
			(end 0.12065 0.2794)
			(stroke
				(width 0.1)
				(type default)
			)
			(layer "B.Fab")
		)
		(fp_line
			(start 0.12065 0.2794)
			(end 0.12065 0.3048)
			(stroke
				(width 0.1)
				(type default)
			)
			(layer "B.Fab")
		)
		(fp_line
			(start -0.12065 -0.2794)
			(end -0.12065 -0.3048)
			(stroke
				(width 0.1)
				(type default)
			)
			(layer "B.Fab")
		)
		(fp_line
			(start 0.12065 -0.2794)
			(end -0.12065 -0.2794)
			(stroke
				(width 0.1)
				(type default)
			)
			(layer "B.Fab")
		)
		(fp_line
			(start -0.67945 -0.3048)
			(end -0.67945 0.3048)
			(stroke
				(width 0.1)
				(type default)
			)
			(layer "B.Fab")
		)
		(fp_line
			(start -0.12065 -0.3048)
			(end -0.67945 -0.3048)
			(stroke
				(width 0.1)
				(type default)
			)
			(layer "B.Fab")
		)
		(fp_line
			(start 0.12065 -0.305054)
			(end 0.12065 -0.2794)
			(stroke
				(width 0.1)
				(type default)
			)
			(layer "B.Fab")
		)
		(fp_line
			(start 0.67945 -0.305054)
			(end 0.12065 -0.305054)
			(stroke
				(width 0.1)
				(type default)
			)
			(layer "B.Fab")
		)
		(pad "1" smd circle
			(at 0.40005 0 90)
			(size 0 0)
			(layers "B.Cu" "B.Mask" "B.Paste")
			(net "PVDDCR_CPU1_P0_PVCC")
		)
		(pad "2" smd circle
			(at -0.40005 0 90)
			(size 0 0)
			(layers "B.Cu" "B.Mask" "B.Paste")
			(net "PVDDCR_CPU1_P0_VCC4")
		)
	)
	(footprint ""
		(layer "B.Cu")
		(at 33.219644 -349.386398 -90)
		(property "Reference" "PR374"
			(at 0 0 90)
			(layer "B.SilkS")
			(hide yes)
			(effects
				(font
					(size 1.27 1.27)
				)
				(justify mirror)
			)
		)
		(property "Value" ""
			(at 0 0 90)
			(layer "B.Fab")
			(effects
				(font
					(size 1.27 1.27)
				)
				(justify mirror)
			)
		)
		(duplicate_pad_numbers_are_jumpers no)
		(fp_line
			(start -0.7874 0.4064)
			(end 0.7874 0.4064)
			(stroke
				(width 0.1524)
				(type default)
			)
			(layer "B.SilkS")
		)
		(fp_line
			(start 0.7874 0.4064)
			(end 0.7874 -0.4064)
			(stroke
				(width 0.1524)
				(type default)
			)
			(layer "B.SilkS")
		)
		(fp_line
			(start -0.7874 -0.4064)
			(end -0.7874 0.4064)
			(stroke
				(width 0.1524)
				(type default)
			)
			(layer "B.SilkS")
		)
		(fp_line
			(start 0.7874 -0.4064)
			(end -0.7874 -0.4064)
			(stroke
				(width 0.1524)
				(type default)
			)
			(layer "B.SilkS")
		)
		(fp_line
			(start -0.67945 0.3048)
			(end -0.120396 0.3048)
			(stroke
				(width 0.1)
				(type default)
			)
			(layer "B.Fab")
		)
		(fp_line
			(start -0.120396 0.3048)
			(end -0.120396 0.2794)
			(stroke
				(width 0.1)
				(type default)
			)
			(layer "B.Fab")
		)
		(fp_line
			(start 0.12065 0.3048)
			(end 0.67945 0.3048)
			(stroke
				(width 0.1)
				(type default)
			)
			(layer "B.Fab")
		)
		(fp_line
			(start 0.67945 0.3048)
			(end 0.67945 -0.305054)
			(stroke
				(width 0.1)
				(type default)
			)
			(layer "B.Fab")
		)
		(fp_line
			(start -0.120396 0.2794)
			(end 0.12065 0.2794)
			(stroke
				(width 0.1)
				(type default)
			)
			(layer "B.Fab")
		)
		(fp_line
			(start 0.12065 0.2794)
			(end 0.12065 0.3048)
			(stroke
				(width 0.1)
				(type default)
			)
			(layer "B.Fab")
		)
		(fp_line
			(start -0.12065 -0.2794)
			(end -0.12065 -0.3048)
			(stroke
				(width 0.1)
				(type default)
			)
			(layer "B.Fab")
		)
		(fp_line
			(start 0.12065 -0.2794)
			(end -0.12065 -0.2794)
			(stroke
				(width 0.1)
				(type default)
			)
			(layer "B.Fab")
		)
		(fp_line
			(start -0.67945 -0.3048)
			(end -0.67945 0.3048)
			(stroke
				(width 0.1)
				(type default)
			)
			(layer "B.Fab")
		)
		(fp_line
			(start -0.12065 -0.3048)
			(end -0.67945 -0.3048)
			(stroke
				(width 0.1)
				(type default)
			)
			(layer "B.Fab")
		)
		(fp_line
			(start 0.12065 -0.305054)
			(end 0.12065 -0.2794)
			(stroke
				(width 0.1)
				(type default)
			)
			(layer "B.Fab")
		)
		(fp_line
			(start 0.67945 -0.305054)
			(end 0.12065 -0.305054)
			(stroke
				(width 0.1)
				(type default)
			)
			(layer "B.Fab")
		)
		(pad "1" smd circle
			(at 0.40005 0 90)
			(size 0 0)
			(layers "B.Cu" "B.Mask" "B.Paste")
			(net "PVDDIO_P1_VOS3")
		)
		(pad "2" smd circle
			(at -0.40005 0 90)
			(size 0 0)
			(layers "B.Cu" "B.Mask" "B.Paste")
			(net "PVDDIO_P1")
		)
	)
	(footprint ""
		(layer "B.Cu")
		(at 89.614502 -207.41005 90)
		(property "Reference" "R928"
			(at 0 0 90)
			(layer "B.SilkS")
			(hide yes)
			(effects
				(font
					(size 1.27 1.27)
				)
				(justify mirror)
			)
		)
		(property "Value" ""
			(at 0 0 90)
			(layer "B.Fab")
			(effects
				(font
					(size 1.27 1.27)
				)
				(justify mirror)
			)
		)
		(duplicate_pad_numbers_are_jumpers no)
		(fp_line
			(start 0.7874 -0.4064)
			(end -0.7874 -0.4064)
			(stroke
				(width 0.1524)
				(type default)
			)
			(layer "B.SilkS")
		)
		(fp_line
			(start -0.7874 -0.4064)
			(end -0.7874 0.4064)
			(stroke
				(width 0.1524)
				(type default)
			)
			(layer "B.SilkS")
		)
		(fp_line
			(start 0.7874 0.4064)
			(end 0.7874 -0.4064)
			(stroke
				(width 0.1524)
				(type default)
			)
			(layer "B.SilkS")
		)
		(fp_line
			(start -0.7874 0.4064)
			(end 0.7874 0.4064)
			(stroke
				(width 0.1524)
				(type default)
			)
			(layer "B.SilkS")
		)
		(fp_line
			(start 0.67945 -0.305054)
			(end 0.12065 -0.305054)
			(stroke
				(width 0.1)
				(type default)
			)
			(layer "B.Fab")
		)
		(fp_line
			(start 0.12065 -0.305054)
			(end 0.12065 -0.2794)
			(stroke
				(width 0.1)
				(type default)
			)
			(layer "B.Fab")
		)
		(fp_line
			(start -0.12065 -0.3048)
			(end -0.67945 -0.3048)
			(stroke
				(width 0.1)
				(type default)
			)
			(layer "B.Fab")
		)
		(fp_line
			(start -0.67945 -0.3048)
			(end -0.67945 0.3048)
			(stroke
				(width 0.1)
				(type default)
			)
			(layer "B.Fab")
		)
		(fp_line
			(start 0.12065 -0.2794)
			(end -0.12065 -0.2794)
			(stroke
				(width 0.1)
				(type default)
			)
			(layer "B.Fab")
		)
		(fp_line
			(start -0.12065 -0.2794)
			(end -0.12065 -0.3048)
			(stroke
				(width 0.1)
				(type default)
			)
			(layer "B.Fab")
		)
		(fp_line
			(start 0.12065 0.2794)
			(end 0.12065 0.3048)
			(stroke
				(width 0.1)
				(type default)
			)
			(layer "B.Fab")
		)
		(fp_line
			(start -0.120396 0.2794)
			(end 0.12065 0.2794)
			(stroke
				(width 0.1)
				(type default)
			)
			(layer "B.Fab")
		)
		(fp_line
			(start 0.67945 0.3048)
			(end 0.67945 -0.305054)
			(stroke
				(width 0.1)
				(type default)
			)
			(layer "B.Fab")
		)
		(fp_line
			(start 0.12065 0.3048)
			(end 0.67945 0.3048)
			(stroke
				(width 0.1)
				(type default)
			)
			(layer "B.Fab")
		)
		(fp_line
			(start -0.120396 0.3048)
			(end -0.120396 0.2794)
			(stroke
				(width 0.1)
				(type default)
			)
			(layer "B.Fab")
		)
		(fp_line
			(start -0.67945 0.3048)
			(end -0.120396 0.3048)
			(stroke
				(width 0.1)
				(type default)
			)
			(layer "B.Fab")
		)
		(pad "1" smd circle
			(at 0.40005 0 270)
			(size 0 0)
			(layers "B.Cu" "B.Mask" "B.Paste")
			(net "CPU1_XTRIG_R2_L7")
		)
		(pad "2" smd circle
			(at -0.40005 0 270)
			(size 0 0)
			(layers "B.Cu" "B.Mask" "B.Paste")
			(net "CPU1_XTRIG_L7")
		)
	)
	(footprint ""
		(layer "B.Cu")
		(at 123.970034 -271.853152 90)
		(property "Reference" "C2386"
			(at 0 0 90)
			(layer "B.SilkS")
			(hide yes)
			(effects
				(font
					(size 1.27 1.27)
				)
				(justify mirror)
			)
		)
		(property "Value" ""
			(at 0 0 90)
			(layer "B.Fab")
			(effects
				(font
					(size 1.27 1.27)
				)
				(justify mirror)
			)
		)
		(duplicate_pad_numbers_are_jumpers no)
		(fp_line
			(start 0.7874 -0.4064)
			(end -0.7874 -0.4064)
			(stroke
				(width 0.1524)
				(type default)
			)
			(layer "B.SilkS")
		)
		(fp_line
			(start -0.7874 -0.4064)
			(end -0.7874 0.4064)
			(stroke
				(width 0.1524)
				(type default)
			)
			(layer "B.SilkS")
		)
		(fp_line
			(start 0.7874 0.4064)
			(end 0.7874 -0.4064)
			(stroke
				(width 0.1524)
				(type default)
			)
			(layer "B.SilkS")
		)
		(fp_line
			(start -0.7874 0.4064)
			(end 0.7874 0.4064)
			(stroke
				(width 0.1524)
				(type default)
			)
			(layer "B.SilkS")
		)
		(fp_line
			(start 0.67945 -0.305054)
			(end 0.12065 -0.305054)
			(stroke
				(width 0.1)
				(type default)
			)
			(layer "B.Fab")
		)
		(fp_line
			(start 0.12065 -0.305054)
			(end 0.12065 -0.2794)
			(stroke
				(width 0.1)
				(type default)
			)
			(layer "B.Fab")
		)
		(fp_line
			(start -0.12065 -0.3048)
			(end -0.67945 -0.3048)
			(stroke
				(width 0.1)
				(type default)
			)
			(layer "B.Fab")
		)
		(fp_line
			(start -0.67945 -0.3048)
			(end -0.67945 0.3048)
			(stroke
				(width 0.1)
				(type default)
			)
			(layer "B.Fab")
		)
		(fp_line
			(start 0.12065 -0.2794)
			(end -0.12065 -0.2794)
			(stroke
				(width 0.1)
				(type default)
			)
			(layer "B.Fab")
		)
		(fp_line
			(start -0.12065 -0.2794)
			(end -0.12065 -0.3048)
			(stroke
				(width 0.1)
				(type default)
			)
			(layer "B.Fab")
		)
		(fp_line
			(start 0.12065 0.2794)
			(end 0.12065 0.3048)
			(stroke
				(width 0.1)
				(type default)
			)
			(layer "B.Fab")
		)
		(fp_line
			(start -0.120396 0.2794)
			(end 0.12065 0.2794)
			(stroke
				(width 0.1)
				(type default)
			)
			(layer "B.Fab")
		)
		(fp_line
			(start 0.67945 0.3048)
			(end 0.67945 -0.305054)
			(stroke
				(width 0.1)
				(type default)
			)
			(layer "B.Fab")
		)
		(fp_line
			(start 0.12065 0.3048)
			(end 0.67945 0.3048)
			(stroke
				(width 0.1)
				(type default)
			)
			(layer "B.Fab")
		)
		(fp_line
			(start -0.120396 0.3048)
			(end -0.120396 0.2794)
			(stroke
				(width 0.1)
				(type default)
			)
			(layer "B.Fab")
		)
		(fp_line
			(start -0.67945 0.3048)
			(end -0.120396 0.3048)
			(stroke
				(width 0.1)
				(type default)
			)
			(layer "B.Fab")
		)
		(pad "1" smd circle
			(at 0.40005 0 270)
			(size 0 0)
			(layers "B.Cu" "B.Mask" "B.Paste")
			(net "PVDDCR_CPU1_P1")
		)
		(pad "2" smd circle
			(at -0.40005 0 270)
			(size 0 0)
			(layers "B.Cu" "B.Mask" "B.Paste")
			(net "GND")
		)
	)
	(footprint ""
		(layer "B.Cu")
		(at 419.912038 -192.660016 180)
		(property "Reference" "C161"
			(at 0 0 0)
			(layer "B.SilkS")
			(hide yes)
			(effects
				(font
					(size 1.27 1.27)
				)
				(justify mirror)
			)
		)
		(property "Value" ""
			(at 0 0 0)
			(layer "B.Fab")
			(effects
				(font
					(size 1.27 1.27)
				)
				(justify mirror)
			)
		)
		(duplicate_pad_numbers_are_jumpers no)
		(fp_line
			(start 1.524 0.762)
			(end 1.524 -0.762)
			(stroke
				(width 0.1524)
				(type default)
			)
			(layer "B.SilkS")
		)
		(fp_line
			(start 1.524 -0.762)
			(end -1.524 -0.762)
			(stroke
				(width 0.1524)
				(type default)
			)
			(layer "B.SilkS")
		)
		(fp_line
			(start -1.524 0.762)
			(end 1.524 0.762)
			(stroke
				(width 0.1524)
				(type default)
			)
			(layer "B.SilkS")
		)
		(fp_line
			(start -1.524 -0.762)
			(end -1.524 0.762)
			(stroke
				(width 0.1524)
				(type default)
			)
			(layer "B.SilkS")
		)
		(fp_line
			(start 1.1049 0.724916)
			(end -1.1049 0.724916)
			(stroke
				(width 0.1)
				(type default)
			)
			(layer "B.Fab")
		)
		(fp_line
			(start 1.1049 -0.724916)
			(end 1.1049 0.724916)
			(stroke
				(width 0.1)
				(type default)
			)
			(layer "B.Fab")
		)
		(fp_line
			(start -1.1049 0.724916)
			(end -1.1049 -0.724916)
			(stroke
				(width 0.1)
				(type default)
			)
			(layer "B.Fab")
		)
		(fp_line
			(start -1.1049 -0.724916)
			(end 1.1049 -0.724916)
			(stroke
				(width 0.1)
				(type default)
			)
			(layer "B.Fab")
		)
		(pad "1" smd rect
			(at 0.889 0 180)
			(size 1.016 1.27)
			(layers "B.Cu" "B.Mask" "B.Paste")
			(net "P12V_MEM_CPU0")
		)
		(pad "2" smd rect
			(at -0.889 0 180)
			(size 1.016 1.27)
			(layers "B.Cu" "B.Mask" "B.Paste")
			(net "GND")
		)
	)
	(footprint ""
		(layer "B.Cu")
		(at 118.686834 -272.284952 180)
		(property "Reference" "C2356"
			(at 0 0 0)
			(layer "B.SilkS")
			(hide yes)
			(effects
				(font
					(size 1.27 1.27)
				)
				(justify mirror)
			)
		)
		(property "Value" ""
			(at 0 0 0)
			(layer "B.Fab")
			(effects
				(font
					(size 1.27 1.27)
				)
				(justify mirror)
			)
		)
		(duplicate_pad_numbers_are_jumpers no)
		(fp_line
			(start 0.7874 0.4064)
			(end 0.7874 -0.4064)
			(stroke
				(width 0.1524)
				(type default)
			)
			(layer "B.SilkS")
		)
		(fp_line
			(start 0.7874 -0.4064)
			(end -0.7874 -0.4064)
			(stroke
				(width 0.1524)
				(type default)
			)
			(layer "B.SilkS")
		)
		(fp_line
			(start -0.7874 0.4064)
			(end 0.7874 0.4064)
			(stroke
				(width 0.1524)
				(type default)
			)
			(layer "B.SilkS")
		)
		(fp_line
			(start -0.7874 -0.4064)
			(end -0.7874 0.4064)
			(stroke
				(width 0.1524)
				(type default)
			)
			(layer "B.SilkS")
		)
		(fp_line
			(start 0.67945 0.3048)
			(end 0.67945 -0.305054)
			(stroke
				(width 0.1)
				(type default)
			)
			(layer "B.Fab")
		)
		(fp_line
			(start 0.67945 -0.305054)
			(end 0.12065 -0.305054)
			(stroke
				(width 0.1)
				(type default)
			)
			(layer "B.Fab")
		)
		(fp_line
			(start 0.12065 0.3048)
			(end 0.67945 0.3048)
			(stroke
				(width 0.1)
				(type default)
			)
			(layer "B.Fab")
		)
		(fp_line
			(start 0.12065 0.2794)
			(end 0.12065 0.3048)
			(stroke
				(width 0.1)
				(type default)
			)
			(layer "B.Fab")
		)
		(fp_line
			(start 0.12065 -0.2794)
			(end -0.12065 -0.2794)
			(stroke
				(width 0.1)
				(type default)
			)
			(layer "B.Fab")
		)
		(fp_line
			(start 0.12065 -0.305054)
			(end 0.12065 -0.2794)
			(stroke
				(width 0.1)
				(type default)
			)
			(layer "B.Fab")
		)
		(fp_line
			(start -0.120396 0.3048)
			(end -0.120396 0.2794)
			(stroke
				(width 0.1)
				(type default)
			)
			(layer "B.Fab")
		)
		(fp_line
			(start -0.120396 0.2794)
			(end 0.12065 0.2794)
			(stroke
				(width 0.1)
				(type default)
			)
			(layer "B.Fab")
		)
		(fp_line
			(start -0.12065 -0.2794)
			(end -0.12065 -0.3048)
			(stroke
				(width 0.1)
				(type default)
			)
			(layer "B.Fab")
		)
		(fp_line
			(start -0.12065 -0.3048)
			(end -0.67945 -0.3048)
			(stroke
				(width 0.1)
				(type default)
			)
			(layer "B.Fab")
		)
		(fp_line
			(start -0.67945 0.3048)
			(end -0.120396 0.3048)
			(stroke
				(width 0.1)
				(type default)
			)
			(layer "B.Fab")
		)
		(fp_line
			(start -0.67945 -0.3048)
			(end -0.67945 0.3048)
			(stroke
				(width 0.1)
				(type default)
			)
			(layer "B.Fab")
		)
		(pad "1" smd circle
			(at 0.40005 0)
			(size 0 0)
			(layers "B.Cu" "B.Mask" "B.Paste")
			(net "PVDDCR_CPU1_P1")
		)
		(pad "2" smd circle
			(at -0.40005 0)
			(size 0 0)
			(layers "B.Cu" "B.Mask" "B.Paste")
			(net "GND")
		)
	)
)
